(kicad_pcb
	(version 20260206)
	(generator "pcbnew")
	(generator_version "10.0")
	(general
		(thickness 1.6)
		(legacy_teardrops no)
	)
	(paper "A4")
	(title_block
		(title "v2-tray-backplane — ms_tbp_v2.brd")
		(comment 1 "Open CloudServer (Microsoft) / footprints 66-74 of 164")
	)
	(layers
		(0 "F.Cu" signal "TOP")
		(4 "In1.Cu" signal "LYR2")
		(6 "In2.Cu" signal "LYR3")
		(8 "In3.Cu" signal "LYR4")
		(10 "In4.Cu" signal "LYR5")
		(12 "In5.Cu" signal "LYR6")
		(14 "In6.Cu" signal "LYR7")
		(2 "B.Cu" signal "BOTTOM")
		(9 "F.Adhes" user "F.Adhesive")
		(11 "B.Adhes" user "B.Adhesive")
		(13 "F.Paste" user "Package Geometry/Pastemask Top")
		(15 "B.Paste" user "Package Geometry/Pastemask Bottom")
		(5 "F.SilkS" user "Ref Des/Silkscreen Top")
		(7 "B.SilkS" user "Ref Des/Silkscreen Bottom")
		(1 "F.Mask" user "Board Geometry/Soldermask Top")
		(3 "B.Mask" user "Board Geometry/Soldermask Bottom")
		(17 "Dwgs.User" user "User.Drawings")
		(19 "Cmts.User" user "User.Comments")
		(21 "Eco1.User" user "User.Eco1")
		(23 "Eco2.User" user "User.Eco2")
		(25 "Edge.Cuts" user "Board Geometry/Outline")
		(27 "Margin" user)
		(31 "F.CrtYd" user "Package Geometry/Place Bound Top")
		(29 "B.CrtYd" user "Package Geometry/Place Bound Bottom")
		(35 "F.Fab" user "Ref Des/Assembly Top")
		(33 "B.Fab" user "Ref Des/Assembly Bottom")
	)
	(footprint ""
		(layer "F.Cu")
		(at -331.47 7.6708)
		(property "Reference" "R79"
			(at 3.175 -0.1397 0)
			(unlocked yes)
			(layer "F.SilkS")
			(effects
				(font
					(size 0.762 0.5334)
					(thickness 0.1016)
				)
			)
		)
		(property "Value" ""
			(at 0 0 0)
			(layer "F.Fab")
			(effects
				(font
					(size 1.27 1.27)
				)
			)
		)
		(duplicate_pad_numbers_are_jumpers no)
		(fp_line
			(start 0 -0.381)
			(end 0 0.381)
			(stroke
				(width 0.127)
				(type default)
			)
			(layer "F.SilkS")
		)
		(fp_poly
			(pts
				(xy 1.255601 0.6564) (xy -1.255601 0.6564) (xy -1.255601 -0.656399) (xy 1.255601 -0.656399)
			)
			(stroke
				(width 0)
				(type default)
			)
			(fill no)
			(layer "F.CrtYd")
		)
		(fp_line
			(start -0.800001 -0.399999)
			(end -0.800001 0.399999)
			(stroke
				(width 0.1)
				(type default)
			)
			(layer "F.Fab")
		)
		(fp_line
			(start -0.800001 0.399999)
			(end 0.800001 0.399999)
			(stroke
				(width 0.1)
				(type default)
			)
			(layer "F.Fab")
		)
		(fp_line
			(start 0.800001 -0.399999)
			(end -0.800001 -0.399999)
			(stroke
				(width 0.1)
				(type default)
			)
			(layer "F.Fab")
		)
		(fp_line
			(start 0.800001 0.399999)
			(end 0.800001 -0.399999)
			(stroke
				(width 0.1)
				(type default)
			)
			(layer "F.Fab")
		)
		(pad "1" smd rect
			(at -0.650001 0)
			(size 0.7112 0.8128)
			(layers "F.Cu" "F.Mask" "F.Paste")
			(net "ETH40G_B1_LPMODE")
		)
		(pad "2" smd rect
			(at 0.650001 0 180)
			(size 0.7112 0.8128)
			(layers "F.Cu" "F.Mask" "F.Paste")
			(net "GND")
		)
	)
	(footprint ""
		(layer "F.Cu")
		(at -331.47 17.4498 180)
		(property "Reference" "R75"
			(at -3.2004 0.0889 0)
			(unlocked yes)
			(layer "F.SilkS")
			(effects
				(font
					(size 0.762 0.5334)
					(thickness 0.1016)
				)
			)
		)
		(property "Value" ""
			(at 0 0 180)
			(layer "F.Fab")
			(effects
				(font
					(size 1.27 1.27)
				)
			)
		)
		(duplicate_pad_numbers_are_jumpers no)
		(fp_line
			(start 0 -0.381)
			(end 0 0.381)
			(stroke
				(width 0.127)
				(type default)
			)
			(layer "F.SilkS")
		)
		(fp_poly
			(pts
				(xy 1.255601 0.656399) (xy -1.255601 0.656399) (xy -1.255601 -0.6564) (xy 1.255601 -0.6564)
			)
			(stroke
				(width 0)
				(type default)
			)
			(fill no)
			(layer "F.CrtYd")
		)
		(fp_line
			(start 0.800001 0.399999)
			(end 0.800001 -0.399999)
			(stroke
				(width 0.1)
				(type default)
			)
			(layer "F.Fab")
		)
		(fp_line
			(start 0.800001 -0.399999)
			(end -0.800001 -0.399999)
			(stroke
				(width 0.1)
				(type default)
			)
			(layer "F.Fab")
		)
		(fp_line
			(start -0.800001 0.399999)
			(end 0.800001 0.399999)
			(stroke
				(width 0.1)
				(type default)
			)
			(layer "F.Fab")
		)
		(fp_line
			(start -0.800001 -0.399999)
			(end -0.800001 0.399999)
			(stroke
				(width 0.1)
				(type default)
			)
			(layer "F.Fab")
		)
		(pad "1" smd rect
			(at -0.650001 0 180)
			(size 0.7112 0.8128)
			(layers "F.Cu" "F.Mask" "F.Paste")
			(net "SKU_B1_ID2")
		)
		(pad "2" smd rect
			(at 0.650001 0)
			(size 0.7112 0.8128)
			(layers "F.Cu" "F.Mask" "F.Paste")
			(net "ETH40G_B1_RESET_N")
		)
	)
	(footprint ""
		(layer "F.Cu")
		(at -385.826 31.1912 90)
		(property "Reference" "R85"
			(at -0.0508 1.5621 90)
			(unlocked yes)
			(layer "F.SilkS")
			(effects
				(font
					(size 0.762 0.5334)
					(thickness 0.1016)
				)
			)
		)
		(property "Value" ""
			(at 0 0 90)
			(layer "F.Fab")
			(effects
				(font
					(size 1.27 1.27)
				)
			)
		)
		(duplicate_pad_numbers_are_jumpers no)
		(fp_line
			(start 0 -0.381)
			(end 0 0.381)
			(stroke
				(width 0.127)
				(type default)
			)
			(layer "F.SilkS")
		)
		(fp_poly
			(pts
				(xy 1.255601 0.656399) (xy -1.255601 0.656399) (xy -1.255601 -0.6564) (xy 1.255601 -0.6564)
			)
			(stroke
				(width 0)
				(type default)
			)
			(fill no)
			(layer "F.CrtYd")
		)
		(fp_line
			(start 0.800001 -0.399999)
			(end -0.800001 -0.399999)
			(stroke
				(width 0.1)
				(type default)
			)
			(layer "F.Fab")
		)
		(fp_line
			(start -0.800001 -0.399999)
			(end -0.800001 0.399999)
			(stroke
				(width 0.1)
				(type default)
			)
			(layer "F.Fab")
		)
		(fp_line
			(start 0.800001 0.399999)
			(end 0.800001 -0.399999)
			(stroke
				(width 0.1)
				(type default)
			)
			(layer "F.Fab")
		)
		(fp_line
			(start -0.800001 0.399999)
			(end 0.800001 0.399999)
			(stroke
				(width 0.1)
				(type default)
			)
			(layer "F.Fab")
		)
		(pad "1" smd rect
			(at -0.650001 0 90)
			(size 0.7112 0.8128)
			(layers "F.Cu" "F.Mask" "F.Paste")
			(net "GND")
		)
		(pad "2" smd rect
			(at 0.650001 0 270)
			(size 0.7112 0.8128)
			(layers "F.Cu" "F.Mask" "F.Paste")
			(net "BLADE_MATED_B1_N<0>")
		)
	)
	(footprint ""
		(layer "F.Cu")
		(at -266.446 0)
		(property "Reference" "FS9"
			(at 2.413 0.0381 0)
			(unlocked yes)
			(layer "F.SilkS")
			(effects
				(font
					(size 0.762 0.5334)
					(thickness 0.1016)
				)
			)
		)
		(property "Value" ""
			(at 0 0 0)
			(layer "F.Fab")
			(effects
				(font
					(size 1.27 1.27)
				)
			)
		)
		(duplicate_pad_numbers_are_jumpers no)
		(fp_poly
			(pts
				(xy -1.002101 0.504) (xy -1.002101 -0.504) (xy 1.002101 -0.504) (xy 1.002101 0.504)
			)
			(stroke
				(width 0)
				(type default)
			)
			(fill no)
			(layer "F.CrtYd")
		)
		(fp_line
			(start -0.499999 -0.25)
			(end -0.499999 0.25)
			(stroke
				(width 0.1)
				(type default)
			)
			(layer "F.Fab")
		)
		(fp_line
			(start -0.499999 0.25)
			(end 0.499999 0.25)
			(stroke
				(width 0.1)
				(type default)
			)
			(layer "F.Fab")
		)
		(fp_line
			(start 0.499999 -0.25)
			(end -0.499999 -0.25)
			(stroke
				(width 0.1)
				(type default)
			)
			(layer "F.Fab")
		)
		(fp_line
			(start 0.499999 0.25)
			(end 0.499999 -0.25)
			(stroke
				(width 0.1)
				(type default)
			)
			(layer "F.Fab")
		)
		(pad "1" smd rect
			(at -0.459999 0 90)
			(size 0.508 0.5842)
			(layers "F.Cu" "F.Mask" "F.Paste")
			(net "P3V3_B1_QSFP")
		)
		(pad "2" smd rect
			(at 0.459999 0 90)
			(size 0.508 0.5842)
			(layers "F.Cu" "F.Mask" "F.Paste")
			(net "UNNAMED_16_FERRITE_I40_A")
		)
	)
	(footprint ""
		(layer "F.Cu")
		(at -266.192 11.6332 -90)
		(property "Reference" "FS10"
			(at -0.26924 -1.9177 90)
			(unlocked yes)
			(layer "F.SilkS")
			(effects
				(font
					(size 0.762 0.5334)
					(thickness 0.1016)
				)
			)
		)
		(property "Value" ""
			(at 0 0 270)
			(layer "F.Fab")
			(effects
				(font
					(size 1.27 1.27)
				)
			)
		)
		(duplicate_pad_numbers_are_jumpers no)
		(fp_poly
			(pts
				(xy -1.002101 0.504) (xy -1.002101 -0.503999) (xy 1.002101 -0.503999) (xy 1.002101 0.504)
			)
			(stroke
				(width 0)
				(type default)
			)
			(fill no)
			(layer "F.CrtYd")
		)
		(fp_line
			(start -0.499999 0.25)
			(end 0.499999 0.25)
			(stroke
				(width 0.1)
				(type default)
			)
			(layer "F.Fab")
		)
		(fp_line
			(start 0.499999 0.25)
			(end 0.499999 -0.249999)
			(stroke
				(width 0.1)
				(type default)
			)
			(layer "F.Fab")
		)
		(fp_line
			(start -0.499999 -0.249999)
			(end -0.499999 0.25)
			(stroke
				(width 0.1)
				(type default)
			)
			(layer "F.Fab")
		)
		(fp_line
			(start 0.499999 -0.249999)
			(end -0.499999 -0.249999)
			(stroke
				(width 0.1)
				(type default)
			)
			(layer "F.Fab")
		)
		(pad "1" smd rect
			(at -0.459999 0)
			(size 0.508 0.5842)
			(layers "F.Cu" "F.Mask" "F.Paste")
			(net "UNNAMED_16_FERRITE_I46_B")
		)
		(pad "2" smd rect
			(at 0.459999 0)
			(size 0.508 0.5842)
			(layers "F.Cu" "F.Mask" "F.Paste")
			(net "P3V3_B1_QSFP")
		)
	)
	(footprint ""
		(layer "F.Cu")
		(at -269.748 3.048 -90)
		(property "Reference" "C36"
			(at -0.02286 1.15316 90)
			(unlocked yes)
			(layer "F.SilkS")
			(effects
				(font
					(size 0.762 0.5334)
					(thickness 0.1016)
				)
			)
		)
		(property "Value" ""
			(at 0 0 270)
			(layer "F.Fab")
			(effects
				(font
					(size 1.27 1.27)
				)
			)
		)
		(duplicate_pad_numbers_are_jumpers no)
		(fp_line
			(start 0 -0.381)
			(end 0 0.381)
			(stroke
				(width 0.127)
				(type default)
			)
			(layer "F.SilkS")
		)
		(fp_poly
			(pts
				(xy 1.2533 0.6564) (xy -1.253299 0.6564) (xy -1.253299 -0.656399) (xy 1.2533 -0.656399)
			)
			(stroke
				(width 0)
				(type default)
			)
			(fill no)
			(layer "F.CrtYd")
		)
		(fp_line
			(start -0.762 0.381)
			(end 0.762 0.381)
			(stroke
				(width 0.1)
				(type default)
			)
			(layer "F.Fab")
		)
		(fp_line
			(start 0.762 0.381)
			(end 0.762 -0.381)
			(stroke
				(width 0.1)
				(type default)
			)
			(layer "F.Fab")
		)
		(fp_line
			(start -0.762 -0.381)
			(end -0.762 0.381)
			(stroke
				(width 0.1)
				(type default)
			)
			(layer "F.Fab")
		)
		(fp_line
			(start 0.762 -0.381)
			(end -0.762 -0.381)
			(stroke
				(width 0.1)
				(type default)
			)
			(layer "F.Fab")
		)
		(pad "1" smd rect
			(at -0.6477 0 270)
			(size 0.7112 0.8128)
			(layers "F.Cu" "F.Mask" "F.Paste")
			(net "P3V3_40G_B1_VCC_RX")
		)
		(pad "2" smd rect
			(at 0.6477 0 90)
			(size 0.7112 0.8128)
			(layers "F.Cu" "F.Mask" "F.Paste")
			(net "GND")
		)
	)
	(footprint ""
		(layer "F.Cu")
		(at -331.47 10.4648)
		(property "Reference" "R83"
			(at 3.175 0.1143 0)
			(unlocked yes)
			(layer "F.SilkS")
			(effects
				(font
					(size 0.762 0.5334)
					(thickness 0.1016)
				)
			)
		)
		(property "Value" ""
			(at 0 0 0)
			(layer "F.Fab")
			(effects
				(font
					(size 1.27 1.27)
				)
			)
		)
		(duplicate_pad_numbers_are_jumpers no)
		(fp_line
			(start 0 -0.381)
			(end 0 0.381)
			(stroke
				(width 0.127)
				(type default)
			)
			(layer "F.SilkS")
		)
		(fp_poly
			(pts
				(xy 1.255601 0.6564) (xy -1.255601 0.6564) (xy -1.255601 -0.656399) (xy 1.255601 -0.656399)
			)
			(stroke
				(width 0)
				(type default)
			)
			(fill no)
			(layer "F.CrtYd")
		)
		(fp_line
			(start -0.800001 -0.399999)
			(end -0.800001 0.399999)
			(stroke
				(width 0.1)
				(type default)
			)
			(layer "F.Fab")
		)
		(fp_line
			(start -0.800001 0.399999)
			(end 0.800001 0.399999)
			(stroke
				(width 0.1)
				(type default)
			)
			(layer "F.Fab")
		)
		(fp_line
			(start 0.800001 -0.399999)
			(end -0.800001 -0.399999)
			(stroke
				(width 0.1)
				(type default)
			)
			(layer "F.Fab")
		)
		(fp_line
			(start 0.800001 0.399999)
			(end 0.800001 -0.399999)
			(stroke
				(width 0.1)
				(type default)
			)
			(layer "F.Fab")
		)
		(pad "1" smd rect
			(at -0.650001 0)
			(size 0.7112 0.8128)
			(layers "F.Cu" "F.Mask" "F.Paste")
			(net "P3V3_B1_QSFP")
		)
		(pad "2" smd rect
			(at 0.650001 0 180)
			(size 0.7112 0.8128)
			(layers "F.Cu" "F.Mask" "F.Paste")
			(net "ETH40G_B1_RESET_N")
		)
	)
	(footprint ""
		(layer "F.Cu")
		(at -267.109689 36.82998 180)
		(property "Reference" "J10"
			(at 0 11.834899 0)
			(unlocked yes)
			(layer "F.SilkS")
			(effects
				(font
					(size 0.762 0.5334)
					(thickness 0.1016)
				)
			)
		)
		(property "Value" ""
			(at 0 0 180)
			(layer "F.Fab")
			(effects
				(font
					(size 1.27 1.27)
				)
			)
		)
		(duplicate_pad_numbers_are_jumpers no)
		(fp_line
			(start 5.325001 10.870001)
			(end -5.325 10.870001)
			(stroke
				(width 0.127)
				(type default)
			)
			(layer "F.SilkS")
		)
		(fp_line
			(start 5.325001 9.27098)
			(end 5.325001 10.870001)
			(stroke
				(width 0.127)
				(type default)
			)
			(layer "F.SilkS")
		)
		(fp_line
			(start 5.325001 -1.58498)
			(end 5.325001 7.36598)
			(stroke
				(width 0.127)
				(type default)
			)
			(layer "F.SilkS")
		)
		(fp_line
			(start 5.325001 -12.76)
			(end 5.325001 -3.269)
			(stroke
				(width 0.127)
				(type default)
			)
			(layer "F.SilkS")
		)
		(fp_line
			(start 2.775001 -12.76)
			(end 5.325001 -12.76)
			(stroke
				(width 0.127)
				(type default)
			)
			(layer "F.SilkS")
		)
		(fp_line
			(start 2.775001 -42.660001)
			(end 2.775001 -12.76)
			(stroke
				(width 0.127)
				(type default)
			)
			(layer "F.SilkS")
		)
		(fp_line
			(start -2.775 -12.76)
			(end -2.775 -42.660001)
			(stroke
				(width 0.127)
				(type default)
			)
			(layer "F.SilkS")
		)
		(fp_line
			(start -2.775 -42.660001)
			(end 2.775001 -42.660001)
			(stroke
				(width 0.127)
				(type default)
			)
			(layer "F.SilkS")
		)
		(fp_line
			(start -5.325 10.870001)
			(end -5.325 -12.76)
			(stroke
				(width 0.127)
				(type default)
			)
			(layer "F.SilkS")
		)
		(fp_line
			(start -5.325 -12.76)
			(end -2.775 -12.76)
			(stroke
				(width 0.127)
				(type default)
			)
			(layer "F.SilkS")
		)
		(fp_poly
			(pts
				(arc
					(start 7.3152 0)
					(mid -7.3152 0)
					(end 7.3152 0)
				)
			)
			(stroke
				(width 0)
				(type default)
			)
			(fill no)
			(layer "B.CrtYd")
		)
		(fp_poly
			(pts
				(xy 6.324999 11.869999) (xy -6.324998 11.869999) (xy -6.324998 -13.76) (xy -3.774998 -13.76) (xy -3.774998 -43.659999)
				(xy 3.774999 -43.659999) (xy 3.774999 -13.76) (xy 6.324999 -13.76)
			)
			(stroke
				(width 0)
				(type default)
			)
			(fill no)
			(layer "F.CrtYd")
		)
		(fp_line
			(start 5.325001 10.870001)
			(end -5.325 10.870001)
			(stroke
				(width 0.1)
				(type default)
			)
			(layer "F.Fab")
		)
		(fp_line
			(start 5.325001 -12.76)
			(end 5.325001 10.870001)
			(stroke
				(width 0.1)
				(type default)
			)
			(layer "F.Fab")
		)
		(fp_line
			(start 2.775001 -12.76)
			(end 5.325001 -12.76)
			(stroke
				(width 0.1)
				(type default)
			)
			(layer "F.Fab")
		)
		(fp_line
			(start 2.775001 -42.660001)
			(end 2.775001 -12.76)
			(stroke
				(width 0.1)
				(type default)
			)
			(layer "F.Fab")
		)
		(fp_line
			(start -2.775 -12.76)
			(end -2.775 -42.660001)
			(stroke
				(width 0.1)
				(type default)
			)
			(layer "F.Fab")
		)
		(fp_line
			(start -2.775 -42.660001)
			(end 2.775001 -42.660001)
			(stroke
				(width 0.1)
				(type default)
			)
			(layer "F.Fab")
		)
		(fp_line
			(start -5.325 10.870001)
			(end -5.325 -12.76)
			(stroke
				(width 0.1)
				(type default)
			)
			(layer "F.Fab")
		)
		(fp_line
			(start -5.325 -12.76)
			(end -2.775 -12.76)
			(stroke
				(width 0.1)
				(type default)
			)
			(layer "F.Fab")
		)
		(pad "" np_thru_hole circle
			(at 0 -5.629999 180)
			(size 1.27 1.27)
			(drill 3.9624)
			(layers "*.Cu" "*.Mask")
		)
		(pad "" np_thru_hole circle
			(at 0 6.619999 180)
			(size 1.27 1.27)
			(drill 3.9624)
			(layers "*.Cu" "*.Mask")
		)
		(pad "1" thru_hole circle
			(at 0 0 180)
			(size 5.588 5.588)
			(drill 3.9624)
			(layers "*.Cu" "*.Mask")
			(remove_unused_layers no)
			(net "GND")
		)
		(zone
			(layers "F.Cu" "B.Cu" "In1.Cu" "In2.Cu" "In3.Cu" "In4.Cu" "In5.Cu" "In6.Cu")
			(hatch none 0.5)
			(connect_pads
				(clearance 0)
			)
			(min_thickness 0.25)
			(keepout
				(tracks not_allowed)
				(vias allowed)
				(pads allowed)
				(copperpour not_allowed)
				(footprints allowed)
			)
			(placement
				(enabled no)
				(sheetname "")
			)
			(fill
				(thermal_gap 0.5)
				(thermal_bridge_width 0.5)
				(island_removal_mode 0)
			)
			(polygon
				(pts
					(arc
						(start -269.471889 30.20998)
						(mid -264.747489 30.20998)
						(end -269.471889 30.20998)
					)
				)
			)
		)
		(zone
			(layers "F.Cu" "B.Cu" "In1.Cu" "In2.Cu" "In3.Cu" "In4.Cu" "In5.Cu" "In6.Cu")
			(hatch none 0.5)
			(connect_pads
				(clearance 0)
			)
			(min_thickness 0.25)
			(keepout
				(tracks not_allowed)
				(vias allowed)
				(pads allowed)
				(copperpour not_allowed)
				(footprints allowed)
			)
			(placement
				(enabled no)
				(sheetname "")
			)
			(fill
				(thermal_gap 0.5)
				(thermal_bridge_width 0.5)
				(island_removal_mode 0)
			)
			(polygon
				(pts
					(arc
						(start -269.471889 42.459979)
						(mid -264.747489 42.459979)
						(end -269.471889 42.459979)
					)
				)
			)
		)
	)
	(footprint ""
		(layer "F.Cu")
		(at -44.958 -0.254)
		(property "Reference" "FS6"
			(at 3.048 0.0381 0)
			(unlocked yes)
			(layer "F.SilkS")
			(effects
				(font
					(size 0.762 0.5334)
					(thickness 0.1016)
				)
			)
		)
		(property "Value" ""
			(at 0 0 0)
			(layer "F.Fab")
			(effects
				(font
					(size 1.27 1.27)
				)
			)
		)
		(duplicate_pad_numbers_are_jumpers no)
		(fp_poly
			(pts
				(xy -1.002101 0.504) (xy -1.002101 -0.504) (xy 1.002101 -0.504) (xy 1.002101 0.504)
			)
			(stroke
				(width 0)
				(type default)
			)
			(fill no)
			(layer "F.CrtYd")
		)
		(fp_line
			(start -0.499999 -0.25)
			(end -0.499999 0.249999)
			(stroke
				(width 0.1)
				(type default)
			)
			(layer "F.Fab")
		)
		(fp_line
			(start -0.499999 0.249999)
			(end 0.499999 0.249999)
			(stroke
				(width 0.1)
				(type default)
			)
			(layer "F.Fab")
		)
		(fp_line
			(start 0.499999 -0.25)
			(end -0.499999 -0.25)
			(stroke
				(width 0.1)
				(type default)
			)
			(layer "F.Fab")
		)
		(fp_line
			(start 0.499999 0.249999)
			(end 0.499999 -0.25)
			(stroke
				(width 0.1)
				(type default)
			)
			(layer "F.Fab")
		)
		(pad "1" smd rect
			(at -0.459999 0 90)
			(size 0.508 0.5842)
			(layers "F.Cu" "F.Mask" "F.Paste")
			(net "P3V3_B2_QSFP")
		)
		(pad "2" smd rect
			(at 0.459999 0 90)
			(size 0.508 0.5842)
			(layers "F.Cu" "F.Mask" "F.Paste")
			(net "UNNAMED_8_FERRITE_I54_A")
		)
	)
)
